# S9S_MB_2U (Grand Teton) — schematic netlist excerpt (pin names and nets, part order shuffled) for the footprints in the layout excerpt that follows; sources: Cadence DE-HDL packaged netlist, KiCad conversion of 03242023_DA0F0TMBIJ0_F0T_Motherboard_J_brd_V01_OCP.brd

R410  Q_RES  4.7K 1% CHIP  pkg 0402LF  page 153 : A = OCP_SFF_ID0 ; B = GND
C26  Q_CAP  2.2UF 6.3V 20% X6S  pkg C0402  page 90 : A = P3V3_AUX ; B = GND

(kicad_pcb
	(version 20260206)
	(generator "pcbnew")
	(generator_version "10.0")
	(general
		(thickness 1.6)
		(legacy_teardrops no)
	)
	(paper "A4")
	(title_block
		(title "03242023_DA0F0TMBIJ0_F0T_Motherboard_J_brd_V01_OCP.brd")
		(comment 1 "Grand Teton / footprints 5102-5103 of 6105")
	)
	(layers
		(0 "F.Cu" signal "TOP")
		(4 "In1.Cu" signal "GND")
		(6 "In2.Cu" signal "IN1")
		(8 "In3.Cu" signal "GND1")
		(10 "In4.Cu" signal "IN2")
		(12 "In5.Cu" signal "GND2")
		(14 "In6.Cu" signal "IN3")
		(16 "In7.Cu" signal "GND3")
		(18 "In8.Cu" signal "VCC")
		(20 "In9.Cu" signal "VCC1")
		(22 "In10.Cu" signal "GND4")
		(24 "In11.Cu" signal "IN4")
		(26 "In12.Cu" signal "GND5")
		(28 "In13.Cu" signal "IN5")
		(30 "In14.Cu" signal "GND6")
		(32 "In15.Cu" signal "IN6")
		(34 "In16.Cu" signal "GND7")
		(2 "B.Cu" signal "BOTTOM")
		(9 "F.Adhes" user "F.Adhesive")
		(11 "B.Adhes" user "B.Adhesive")
		(13 "F.Paste" user "Package Geometry/Pastemask Top")
		(15 "B.Paste" user "Package Geometry/Pastemask Bottom")
		(5 "F.SilkS" user "Ref Des/Silkscreen Top")
		(7 "B.SilkS" user "Ref Des/Silkscreen Bottom")
		(1 "F.Mask" user "Board Geometry/Soldermask Top")
		(3 "B.Mask" user "Board Geometry/Soldermask Bottom")
		(17 "Dwgs.User" user "User.Drawings")
		(19 "Cmts.User" user "User.Comments")
		(21 "Eco1.User" user "User.Eco1")
		(23 "Eco2.User" user "User.Eco2")
		(25 "Edge.Cuts" user "Board Geometry/Outline")
		(27 "Margin" user)
		(31 "F.CrtYd" user "Package Geometry/Place Bound Top")
		(29 "B.CrtYd" user "Package Geometry/Place Bound Bottom")
		(35 "F.Fab" user "Ref Des/Assembly Top")
		(33 "B.Fab" user "Ref Des/Assembly Bottom")
	)
	(footprint ""
		(layer "B.Cu")
		(at 414.309814 -319.263776 180)
		(property "Reference" "C26"
			(at 0 0 0)
			(layer "B.SilkS")
			(hide yes)
			(effects
				(font
					(size 1.27 1.27)
				)
				(justify mirror)
			)
		)
		(property "Value" ""
			(at 0 0 0)
			(layer "B.Fab")
			(effects
				(font
					(size 1.27 1.27)
				)
				(justify mirror)
			)
		)
		(duplicate_pad_numbers_are_jumpers no)
		(fp_line
			(start 0.7874 0.4064)
			(end 0.7874 -0.4064)
			(stroke
				(width 0.1524)
				(type default)
			)
			(layer "B.SilkS")
		)
		(fp_line
			(start 0.7874 -0.4064)
			(end -0.7874 -0.4064)
			(stroke
				(width 0.1524)
				(type default)
			)
			(layer "B.SilkS")
		)
		(fp_line
			(start -0.7874 0.4064)
			(end 0.7874 0.4064)
			(stroke
				(width 0.1524)
				(type default)
			)
			(layer "B.SilkS")
		)
		(fp_line
			(start -0.7874 -0.4064)
			(end -0.7874 0.4064)
			(stroke
				(width 0.1524)
				(type default)
			)
			(layer "B.SilkS")
		)
		(fp_line
			(start 0.67945 0.3048)
			(end 0.67945 -0.305054)
			(stroke
				(width 0.1)
				(type default)
			)
			(layer "B.Fab")
		)
		(fp_line
			(start 0.67945 -0.305054)
			(end 0.12065 -0.305054)
			(stroke
				(width 0.1)
				(type default)
			)
			(layer "B.Fab")
		)
		(fp_line
			(start 0.12065 0.3048)
			(end 0.67945 0.3048)
			(stroke
				(width 0.1)
				(type default)
			)
			(layer "B.Fab")
		)
		(fp_line
			(start 0.12065 0.2794)
			(end 0.12065 0.3048)
			(stroke
				(width 0.1)
				(type default)
			)
			(layer "B.Fab")
		)
		(fp_line
			(start 0.12065 -0.2794)
			(end -0.12065 -0.2794)
			(stroke
				(width 0.1)
				(type default)
			)
			(layer "B.Fab")
		)
		(fp_line
			(start 0.12065 -0.305054)
			(end 0.12065 -0.2794)
			(stroke
				(width 0.1)
				(type default)
			)
			(layer "B.Fab")
		)
		(fp_line
			(start -0.120396 0.3048)
			(end -0.120396 0.2794)
			(stroke
				(width 0.1)
				(type default)
			)
			(layer "B.Fab")
		)
		(fp_line
			(start -0.120396 0.2794)
			(end 0.12065 0.2794)
			(stroke
				(width 0.1)
				(type default)
			)
			(layer "B.Fab")
		)
		(fp_line
			(start -0.12065 -0.2794)
			(end -0.12065 -0.3048)
			(stroke
				(width 0.1)
				(type default)
			)
			(layer "B.Fab")
		)
		(fp_line
			(start -0.12065 -0.3048)
			(end -0.67945 -0.3048)
			(stroke
				(width 0.1)
				(type default)
			)
			(layer "B.Fab")
		)
		(fp_line
			(start -0.67945 0.3048)
			(end -0.120396 0.3048)
			(stroke
				(width 0.1)
				(type default)
			)
			(layer "B.Fab")
		)
		(fp_line
			(start -0.67945 -0.3048)
			(end -0.67945 0.3048)
			(stroke
				(width 0.1)
				(type default)
			)
			(layer "B.Fab")
		)
		(pad "1" smd circle
			(at 0.40005 0)
			(size 0 0)
			(layers "B.Cu" "B.Mask" "B.Paste")
			(net "P3V3_AUX")
		)
		(pad "2" smd circle
			(at -0.40005 0)
			(size 0 0)
			(layers "B.Cu" "B.Mask" "B.Paste")
			(net "GND")
		)
	)
	(footprint ""
		(layer "B.Cu")
		(at 447.56705 -10.594086 90)
		(property "Reference" "R410"
			(at 0 0 90)
			(layer "B.SilkS")
			(hide yes)
			(effects
				(font
					(size 1.27 1.27)
				)
				(justify mirror)
			)
		)
		(property "Value" ""
			(at 0 0 90)
			(layer "B.Fab")
			(effects
				(font
					(size 1.27 1.27)
				)
				(justify mirror)
			)
		)
		(duplicate_pad_numbers_are_jumpers no)
		(fp_line
			(start 0.7874 -0.4064)
			(end -0.7874 -0.4064)
			(stroke
				(width 0.1524)
				(type default)
			)
			(layer "B.SilkS")
		)
		(fp_line
			(start -0.7874 -0.4064)
			(end -0.7874 0.4064)
			(stroke
				(width 0.1524)
				(type default)
			)
			(layer "B.SilkS")
		)
		(fp_line
			(start 0.7874 0.4064)
			(end 0.7874 -0.4064)
			(stroke
				(width 0.1524)
				(type default)
			)
			(layer "B.SilkS")
		)
		(fp_line
			(start -0.7874 0.4064)
			(end 0.7874 0.4064)
			(stroke
				(width 0.1524)
				(type default)
			)
			(layer "B.SilkS")
		)
		(fp_line
			(start 0.67945 -0.305054)
			(end 0.12065 -0.305054)
			(stroke
				(width 0.1)
				(type default)
			)
			(layer "B.Fab")
		)
		(fp_line
			(start 0.12065 -0.305054)
			(end 0.12065 -0.2794)
			(stroke
				(width 0.1)
				(type default)
			)
			(layer "B.Fab")
		)
		(fp_line
			(start -0.12065 -0.3048)
			(end -0.67945 -0.3048)
			(stroke
				(width 0.1)
				(type default)
			)
			(layer "B.Fab")
		)
		(fp_line
			(start -0.67945 -0.3048)
			(end -0.67945 0.3048)
			(stroke
				(width 0.1)
				(type default)
			)
			(layer "B.Fab")
		)
		(fp_line
			(start 0.12065 -0.2794)
			(end -0.12065 -0.2794)
			(stroke
				(width 0.1)
				(type default)
			)
			(layer "B.Fab")
		)
		(fp_line
			(start -0.12065 -0.2794)
			(end -0.12065 -0.3048)
			(stroke
				(width 0.1)
				(type default)
			)
			(layer "B.Fab")
		)
		(fp_line
			(start 0.12065 0.2794)
			(end 0.12065 0.3048)
			(stroke
				(width 0.1)
				(type default)
			)
			(layer "B.Fab")
		)
		(fp_line
			(start -0.120396 0.2794)
			(end 0.12065 0.2794)
			(stroke
				(width 0.1)
				(type default)
			)
			(layer "B.Fab")
		)
		(fp_line
			(start 0.67945 0.3048)
			(end 0.67945 -0.305054)
			(stroke
				(width 0.1)
				(type default)
			)
			(layer "B.Fab")
		)
		(fp_line
			(start 0.12065 0.3048)
			(end 0.67945 0.3048)
			(stroke
				(width 0.1)
				(type default)
			)
			(layer "B.Fab")
		)
		(fp_line
			(start -0.120396 0.3048)
			(end -0.120396 0.2794)
			(stroke
				(width 0.1)
				(type default)
			)
			(layer "B.Fab")
		)
		(fp_line
			(start -0.67945 0.3048)
			(end -0.120396 0.3048)
			(stroke
				(width 0.1)
				(type default)
			)
			(layer "B.Fab")
		)
		(pad "1" smd circle
			(at 0.40005 0 270)
			(size 0 0)
			(layers "B.Cu" "B.Mask" "B.Paste")
			(net "OCP_SFF_ID0")
		)
		(pad "2" smd circle
			(at -0.40005 0 270)
			(size 0 0)
			(layers "B.Cu" "B.Mask" "B.Paste")
			(net "GND")
		)
	)
)
